FILE_TYPE = CONNECTIVITY;
{Allegro Design Entry HDL 17.2-2016 S081 (4005846) 1/11/2022}
"PAGE_NUMBER" = 32;
0"NC";
1"UPI_CPU0_CPU1_P0P1_DP<23:0>";
2"UPI_CPU0_CPU1_P0P1_DN<23:0>";
3"UPI_CPU1_CPU0_P1P0_DP<23:0>";
4"UPI_CPU1_CPU0_P1P0_DN<23:0>";
5"UPI_CPU1_CPU0_P1P0_DP<23>";
6"UPI_CPU1_CPU0_P1P0_DN<22>";
7"UPI_CPU1_CPU0_P1P0_DP<21>";
8"UPI_CPU1_CPU0_P1P0_DP<20>";
9"UPI_CPU1_CPU0_P1P0_DP<19>";
10"UPI_CPU1_CPU0_P1P0_DP<18>";
11"UPI_CPU1_CPU0_P1P0_DP<17>";
12"UPI_CPU1_CPU0_P1P0_DP<16>";
13"UPI_CPU1_CPU0_P1P0_DP<15>";
14"UPI_CPU1_CPU0_P1P0_DP<14>";
15"UPI_CPU1_CPU0_P1P0_DP<13>";
16"UPI_CPU1_CPU0_P1P0_DP<12>";
17"UPI_CPU1_CPU0_P1P0_DP<11>";
18"UPI_CPU1_CPU0_P1P0_DP<10>";
19"UPI_CPU1_CPU0_P1P0_DN<9>";
20"UPI_CPU1_CPU0_P1P0_DN<8>";
21"UPI_CPU1_CPU0_P1P0_DN<7>";
22"UPI_CPU1_CPU0_P1P0_DN<6>";
23"UPI_CPU1_CPU0_P1P0_DP<5>";
24"UPI_CPU1_CPU0_P1P0_DN<4>";
25"UPI_CPU1_CPU0_P1P0_DP<3>";
26"UPI_CPU1_CPU0_P1P0_DN<2>";
27"UPI_CPU1_CPU0_P1P0_DN<1>";
28"UPI_CPU1_CPU0_P1P0_DN<0>";
29"UPI_CPU1_CPU0_P1P0_DN<23>";
30"UPI_CPU1_CPU0_P1P0_DP<22>";
31"UPI_CPU1_CPU0_P1P0_DN<21>";
32"UPI_CPU1_CPU0_P1P0_DN<20>";
33"UPI_CPU1_CPU0_P1P0_DN<19>";
34"UPI_CPU1_CPU0_P1P0_DN<18>";
35"UPI_CPU1_CPU0_P1P0_DN<17>";
36"UPI_CPU1_CPU0_P1P0_DN<16>";
37"UPI_CPU1_CPU0_P1P0_DN<15>";
38"UPI_CPU1_CPU0_P1P0_DN<14>";
39"UPI_CPU1_CPU0_P1P0_DN<13>"$PNN"UPI_CPU1_CPU0_P1P0_DP<13>";
40"UPI_CPU1_CPU0_P1P0_DN<12>"$PNN"UPI_CPU1_CPU0_P1P0_DP<12>";
41"UPI_CPU1_CPU0_P1P0_DN<11>";
42"UPI_CPU1_CPU0_P1P0_DN<10>";
43"UPI_CPU1_CPU0_P1P0_DP<9>";
44"UPI_CPU1_CPU0_P1P0_DP<8>";
45"UPI_CPU1_CPU0_P1P0_DP<7>";
46"UPI_CPU1_CPU0_P1P0_DP<6>";
47"UPI_CPU1_CPU0_P1P0_DN<5>";
48"UPI_CPU1_CPU0_P1P0_DP<4>";
49"UPI_CPU1_CPU0_P1P0_DN<3>";
50"UPI_CPU1_CPU0_P1P0_DP<2>";
51"UPI_CPU1_CPU0_P1P0_DP<1>";
52"UPI_CPU1_CPU0_P1P0_DP<0>";
53"UPI_CPU0_CPU1_P0P1_DN<23>";
54"UPI_CPU0_CPU1_P0P1_DP<22>";
55"UPI_CPU0_CPU1_P0P1_DP<21>";
56"UPI_CPU0_CPU1_P0P1_DP<20>";
57"UPI_CPU0_CPU1_P0P1_DN<19>";
58"UPI_CPU0_CPU1_P0P1_DN<18>";
59"UPI_CPU0_CPU1_P0P1_DN<17>";
60"UPI_CPU0_CPU1_P0P1_DN<16>";
61"UPI_CPU0_CPU1_P0P1_DP<15>";
62"UPI_CPU0_CPU1_P0P1_DN<14>";
63"UPI_CPU0_CPU1_P0P1_DP<13>";
64"UPI_CPU0_CPU1_P0P1_DP<12>";
65"UPI_CPU0_CPU1_P0P1_DN<11>";
66"UPI_CPU0_CPU1_P0P1_DN<10>";
67"UPI_CPU0_CPU1_P0P1_DN<9>";
68"UPI_CPU0_CPU1_P0P1_DN<8>";
69"UPI_CPU0_CPU1_P0P1_DN<7>";
70"UPI_CPU0_CPU1_P0P1_DN<6>";
71"UPI_CPU0_CPU1_P0P1_DN<5>";
72"UPI_CPU0_CPU1_P0P1_DN<4>";
73"UPI_CPU0_CPU1_P0P1_DN<3>";
74"UPI_CPU0_CPU1_P0P1_DN<2>";
75"UPI_CPU0_CPU1_P0P1_DN<1>";
76"UPI_CPU0_CPU1_P0P1_DN<0>";
77"UPI_CPU0_CPU1_P0P1_DP<23>";
78"UPI_CPU0_CPU1_P0P1_DN<22>";
79"UPI_CPU0_CPU1_P0P1_DN<21>";
80"UPI_CPU0_CPU1_P0P1_DN<20>";
81"UPI_CPU0_CPU1_P0P1_DP<19>";
82"UPI_CPU0_CPU1_P0P1_DP<18>";
83"UPI_CPU0_CPU1_P0P1_DP<17>";
84"UPI_CPU0_CPU1_P0P1_DP<16>";
85"UPI_CPU0_CPU1_P0P1_DN<15>";
86"UPI_CPU0_CPU1_P0P1_DP<14>";
87"UPI_CPU0_CPU1_P0P1_DN<13>";
88"UPI_CPU0_CPU1_P0P1_DN<12>";
89"UPI_CPU0_CPU1_P0P1_DP<11>";
90"UPI_CPU0_CPU1_P0P1_DP<10>";
91"UPI_CPU0_CPU1_P0P1_DP<9>";
92"UPI_CPU0_CPU1_P0P1_DP<8>";
93"UPI_CPU0_CPU1_P0P1_DP<7>";
94"UPI_CPU0_CPU1_P0P1_DP<6>";
95"UPI_CPU0_CPU1_P0P1_DP<5>";
96"UPI_CPU0_CPU1_P0P1_DP<4>";
97"UPI_CPU0_CPU1_P0P1_DP<3>";
98"UPI_CPU0_CPU1_P0P1_DP<2>";
99"UPI_CPU0_CPU1_P0P1_DP<1>";
100"UPI_CPU0_CPU1_P0P1_DP<0>";
%"TAP"
"1","(-400,2725)","2","standard","I101";
;
CDS_LIB"standard"
BODY_TYPE"PLUMBING"
HDL_TAP"TRUE";
"B \NAC \NWC"3;
"S \NAC"
BN"4"48;
%"TAP"
"1","(-400,2525)","2","standard","I102";
;
CDS_LIB"standard"
BODY_TYPE"PLUMBING"
HDL_TAP"TRUE";
"B \NAC \NWC"3;
"S \NAC"
BN"0"52;
%"TAP"
"1","(-400,2825)","2","standard","I103";
;
CDS_LIB"standard"
BODY_TYPE"PLUMBING"
HDL_TAP"TRUE";
"B \NAC \NWC"3;
"S \NAC"
BN"6"46;
%"TAP"
"1","(-400,2875)","2","standard","I104";
;
CDS_LIB"standard"
BODY_TYPE"PLUMBING"
HDL_TAP"TRUE";
"B \NAC \NWC"3;
"S \NAC"
BN"7"45;
%"TAP"
"1","(2975,2375)","0","standard","I106";
;
CDS_LIB"standard"
BODY_TYPE"PLUMBING"
HDL_TAP"TRUE";
"B \NAC \NWC"1;
"S \NAC"
BN"22"54;
%"TAP"
"1","(3175,2425)","0","standard","I107";
;
CDS_LIB"standard"
BODY_TYPE"PLUMBING"
HDL_TAP"TRUE";
"B \NAC \NWC"2;
"S \NAC"
BN"23"53;
%"TAP"
"1","(2975,2325)","0","standard","I108";
;
CDS_LIB"standard"
BODY_TYPE"PLUMBING"
HDL_TAP"TRUE";
"B \NAC \NWC"1;
"S \NAC"
BN"21"55;
%"TAP"
"1","(2975,2275)","0","standard","I109";
;
CDS_LIB"standard"
BODY_TYPE"PLUMBING"
HDL_TAP"TRUE";
"B \NAC \NWC"1;
"S \NAC"
BN"20"56;
%"TAP"
"1","(3175,2225)","0","standard","I110";
;
CDS_LIB"standard"
BODY_TYPE"PLUMBING"
HDL_TAP"TRUE";
"B \NAC \NWC"2;
"S \NAC"
BN"19"57;
%"TAP"
"1","(3175,2175)","0","standard","I111";
;
CDS_LIB"standard"
BODY_TYPE"PLUMBING"
HDL_TAP"TRUE";
"B \NAC \NWC"2;
"S \NAC"
BN"18"58;
%"TAP"
"1","(3175,2125)","0","standard","I112";
;
CDS_LIB"standard"
BODY_TYPE"PLUMBING"
HDL_TAP"TRUE";
"B \NAC \NWC"2;
"S \NAC"
BN"17"59;
%"TAP"
"1","(3175,2075)","0","standard","I113";
;
CDS_LIB"standard"
BODY_TYPE"PLUMBING"
HDL_TAP"TRUE";
"B \NAC \NWC"2;
"S \NAC"
BN"16"60;
%"TAP"
"1","(3175,1975)","0","standard","I114";
;
CDS_LIB"standard"
BODY_TYPE"PLUMBING"
HDL_TAP"TRUE";
"B \NAC \NWC"2;
"S \NAC"
BN"14"62;
%"TAP"
"1","(2975,1925)","0","standard","I115";
;
CDS_LIB"standard"
BODY_TYPE"PLUMBING"
HDL_TAP"TRUE";
"B \NAC \NWC"1;
"S \NAC"
BN"13"63;
%"TAP"
"1","(2975,2025)","0","standard","I116";
;
CDS_LIB"standard"
BODY_TYPE"PLUMBING"
HDL_TAP"TRUE";
"B \NAC \NWC"1;
"S \NAC"
BN"15"61;
%"TAP"
"1","(2975,1875)","0","standard","I117";
;
CDS_LIB"standard"
BODY_TYPE"PLUMBING"
HDL_TAP"TRUE";
"B \NAC \NWC"1;
"S \NAC"
BN"12"64;
%"TAP"
"1","(3175,1825)","0","standard","I118";
;
CDS_LIB"standard"
BODY_TYPE"PLUMBING"
HDL_TAP"TRUE";
"B \NAC \NWC"2;
"S \NAC"
BN"11"65;
%"TAP"
"1","(3175,1725)","0","standard","I119";
;
CDS_LIB"standard"
BODY_TYPE"PLUMBING"
HDL_TAP"TRUE";
"B \NAC \NWC"2;
"S \NAC"
BN"9"67;
%"TAP"
"1","(3175,1675)","0","standard","I120";
;
CDS_LIB"standard"
BODY_TYPE"PLUMBING"
HDL_TAP"TRUE";
"B \NAC \NWC"2;
"S \NAC"
BN"8"68;
%"TAP"
"1","(3175,1775)","0","standard","I121";
;
CDS_LIB"standard"
BODY_TYPE"PLUMBING"
HDL_TAP"TRUE";
"B \NAC \NWC"2;
"S \NAC"
BN"10"66;
%"TAP"
"1","(3175,1425)","0","standard","I122";
;
CDS_LIB"standard"
BODY_TYPE"PLUMBING"
HDL_TAP"TRUE";
"B \NAC \NWC"2;
"S \NAC"
BN"3"73;
%"TAP"
"1","(3175,1475)","0","standard","I123";
;
CDS_LIB"standard"
BODY_TYPE"PLUMBING"
HDL_TAP"TRUE";
"B \NAC \NWC"2;
"S \NAC"
BN"4"72;
%"TAP"
"1","(3175,1525)","0","standard","I124";
;
CDS_LIB"standard"
BODY_TYPE"PLUMBING"
HDL_TAP"TRUE";
"B \NAC \NWC"2;
"S \NAC"
BN"5"71;
%"TAP"
"1","(3175,1575)","0","standard","I125";
;
CDS_LIB"standard"
BODY_TYPE"PLUMBING"
HDL_TAP"TRUE";
"B \NAC \NWC"2;
"S \NAC"
BN"6"70;
%"TAP"
"1","(3175,1625)","0","standard","I126";
;
CDS_LIB"standard"
BODY_TYPE"PLUMBING"
HDL_TAP"TRUE";
"B \NAC \NWC"2;
"S \NAC"
BN"7"69;
%"TAP"
"1","(3175,1325)","0","standard","I127";
;
CDS_LIB"standard"
BODY_TYPE"PLUMBING"
HDL_TAP"TRUE";
"B \NAC \NWC"2;
"S \NAC"
BN"1"75;
%"TAP"
"1","(3175,1275)","0","standard","I128";
;
CDS_LIB"standard"
BODY_TYPE"PLUMBING"
HDL_TAP"TRUE";
"B \NAC \NWC"2;
"S \NAC"
BN"0"76;
%"TAP"
"1","(3175,1375)","0","standard","I129";
;
CDS_LIB"standard"
BODY_TYPE"PLUMBING"
HDL_TAP"TRUE";
"B \NAC \NWC"2;
"S \NAC"
BN"2"74;
%"TAP"
"1","(2975,2725)","0","standard","I130";
;
CDS_LIB"standard"
BODY_TYPE"PLUMBING"
HDL_TAP"TRUE";
"B \NAC \NWC"1;
"S \NAC"
BN"4"96;
%"TAP"
"1","(2975,2675)","0","standard","I131";
;
CDS_LIB"standard"
BODY_TYPE"PLUMBING"
HDL_TAP"TRUE";
"B \NAC \NWC"1;
"S \NAC"
BN"3"97;
%"TAP"
"1","(2975,2775)","0","standard","I132";
;
CDS_LIB"standard"
BODY_TYPE"PLUMBING"
HDL_TAP"TRUE";
"B \NAC \NWC"1;
"S \NAC"
BN"5"95;
%"TAP"
"1","(2975,2825)","0","standard","I133";
;
CDS_LIB"standard"
BODY_TYPE"PLUMBING"
HDL_TAP"TRUE";
"B \NAC \NWC"1;
"S \NAC"
BN"6"94;
%"TAP"
"1","(2975,2875)","0","standard","I134";
;
CDS_LIB"standard"
BODY_TYPE"PLUMBING"
HDL_TAP"TRUE";
"B \NAC \NWC"1;
"S \NAC"
BN"7"93;
%"TAP"
"1","(2975,2625)","0","standard","I135";
;
CDS_LIB"standard"
BODY_TYPE"PLUMBING"
HDL_TAP"TRUE";
"B \NAC \NWC"1;
"S \NAC"
BN"2"98;
%"TAP"
"1","(2975,2525)","0","standard","I136";
;
CDS_LIB"standard"
BODY_TYPE"PLUMBING"
HDL_TAP"TRUE";
"B \NAC \NWC"1;
"S \NAC"
BN"0"100;
%"TAP"
"1","(2975,2575)","0","standard","I137";
;
CDS_LIB"standard"
BODY_TYPE"PLUMBING"
HDL_TAP"TRUE";
"B \NAC \NWC"1;
"S \NAC"
BN"1"99;
%"TAP"
"1","(3175,3575)","0","standard","I139";
;
CDS_LIB"standard"
BODY_TYPE"PLUMBING"
HDL_TAP"TRUE";
"B \NAC \NWC"2;
"S \NAC"
BN"21"79;
%"TAP"
"1","(3175,3625)","0","standard","I140";
;
CDS_LIB"standard"
BODY_TYPE"PLUMBING"
HDL_TAP"TRUE";
"B \NAC \NWC"2;
"S \NAC"
BN"22"78;
%"TAP"
"1","(3175,3525)","0","standard","I141";
;
CDS_LIB"standard"
BODY_TYPE"PLUMBING"
HDL_TAP"TRUE";
"B \NAC \NWC"2;
"S \NAC"
BN"20"80;
%"TAP"
"1","(3175,3175)","0","standard","I142";
;
CDS_LIB"standard"
BODY_TYPE"PLUMBING"
HDL_TAP"TRUE";
"B \NAC \NWC"2;
"S \NAC"
BN"13"87;
%"TAP"
"1","(3175,3275)","0","standard","I143";
;
CDS_LIB"standard"
BODY_TYPE"PLUMBING"
HDL_TAP"TRUE";
"B \NAC \NWC"2;
"S \NAC"
BN"15"85;
%"TAP"
"1","(3175,3125)","0","standard","I144";
;
CDS_LIB"standard"
BODY_TYPE"PLUMBING"
HDL_TAP"TRUE";
"B \NAC \NWC"2;
"S \NAC"
BN"12"88;
%"TAP"
"1","(-575,3125)","2","standard","I146";
;
CDS_LIB"standard"
BODY_TYPE"PLUMBING"
HDL_TAP"TRUE";
"B \NAC \NWC"4;
"S \NAC"
BN"12"40;
%"TAP"
"1","(-400,1875)","2","standard","I147";
;
CDS_LIB"standard"
BODY_TYPE"PLUMBING"
HDL_TAP"TRUE";
"B \NAC \NWC"3;
"S \NAC"
BN"12"16;
%"TAP"
"1","(-575,3175)","2","standard","I148";
;
CDS_LIB"standard"
BODY_TYPE"PLUMBING"
HDL_TAP"TRUE";
"B \NAC \NWC"4;
"S \NAC"
BN"13"39;
%"TAP"
"1","(-400,1925)","2","standard","I149";
;
CDS_LIB"standard"
BODY_TYPE"PLUMBING"
HDL_TAP"TRUE";
"B \NAC \NWC"3;
"S \NAC"
BN"13"15;
%"TAP"
"1","(-575,3525)","2","standard","I150";
;
CDS_LIB"standard"
BODY_TYPE"PLUMBING"
HDL_TAP"TRUE";
"B \NAC \NWC"4;
"S \NAC"
BN"20"32;
%"TAP"
"1","(-575,3475)","2","standard","I151";
;
CDS_LIB"standard"
BODY_TYPE"PLUMBING"
HDL_TAP"TRUE";
"B \NAC \NWC"4;
"S \NAC"
BN"19"33;
%"TAP"
"1","(-575,3425)","2","standard","I152";
;
CDS_LIB"standard"
BODY_TYPE"PLUMBING"
HDL_TAP"TRUE";
"B \NAC \NWC"4;
"S \NAC"
BN"18"34;
%"TAP"
"1","(-575,3375)","2","standard","I153";
;
CDS_LIB"standard"
BODY_TYPE"PLUMBING"
HDL_TAP"TRUE";
"B \NAC \NWC"4;
"S \NAC"
BN"17"35;
%"TAP"
"1","(-575,3325)","2","standard","I154";
;
CDS_LIB"standard"
BODY_TYPE"PLUMBING"
HDL_TAP"TRUE";
"B \NAC \NWC"4;
"S \NAC"
BN"16"36;
%"TAP"
"1","(-575,3275)","2","standard","I155";
;
CDS_LIB"standard"
BODY_TYPE"PLUMBING"
HDL_TAP"TRUE";
"B \NAC \NWC"4;
"S \NAC"
BN"15"37;
%"TAP"
"1","(-575,3225)","2","standard","I156";
;
CDS_LIB"standard"
BODY_TYPE"PLUMBING"
HDL_TAP"TRUE";
"B \NAC \NWC"4;
"S \NAC"
BN"14"38;
%"TAP"
"1","(-400,2275)","2","standard","I157";
;
CDS_LIB"standard"
BODY_TYPE"PLUMBING"
HDL_TAP"TRUE";
"B \NAC \NWC"3;
"S \NAC"
BN"20"8;
%"TAP"
"1","(-400,2225)","2","standard","I158";
;
CDS_LIB"standard"
BODY_TYPE"PLUMBING"
HDL_TAP"TRUE";
"B \NAC \NWC"3;
"S \NAC"
BN"19"9;
%"TAP"
"1","(-400,2175)","2","standard","I159";
;
CDS_LIB"standard"
BODY_TYPE"PLUMBING"
HDL_TAP"TRUE";
"B \NAC \NWC"3;
"S \NAC"
BN"18"10;
%"TAP"
"1","(-400,2125)","2","standard","I160";
;
CDS_LIB"standard"
BODY_TYPE"PLUMBING"
HDL_TAP"TRUE";
"B \NAC \NWC"3;
"S \NAC"
BN"17"11;
%"TAP"
"1","(-400,2075)","2","standard","I161";
;
CDS_LIB"standard"
BODY_TYPE"PLUMBING"
HDL_TAP"TRUE";
"B \NAC \NWC"3;
"S \NAC"
BN"16"12;
%"TAP"
"1","(-400,2025)","2","standard","I162";
;
CDS_LIB"standard"
BODY_TYPE"PLUMBING"
HDL_TAP"TRUE";
"B \NAC \NWC"3;
"S \NAC"
BN"15"13;
%"TAP"
"1","(-400,1975)","2","standard","I163";
;
CDS_LIB"standard"
BODY_TYPE"PLUMBING"
HDL_TAP"TRUE";
"B \NAC \NWC"3;
"S \NAC"
BN"14"14;
%"TAP"
"1","(-575,3675)","2","standard","I165";
;
CDS_LIB"standard"
BODY_TYPE"PLUMBING"
HDL_TAP"TRUE";
"B \NAC \NWC"4;
"S \NAC"
BN"23"29;
%"TAP"
"1","(-575,3575)","2","standard","I166";
;
CDS_LIB"standard"
BODY_TYPE"PLUMBING"
HDL_TAP"TRUE";
"B \NAC \NWC"4;
"S \NAC"
BN"21"31;
%"TAP"
"1","(-400,2425)","2","standard","I167";
;
CDS_LIB"standard"
BODY_TYPE"PLUMBING"
HDL_TAP"TRUE";
"B \NAC \NWC"3;
"S \NAC"
BN"23"5;
%"TAP"
"1","(-400,2325)","2","standard","I168";
;
CDS_LIB"standard"
BODY_TYPE"PLUMBING"
HDL_TAP"TRUE";
"B \NAC \NWC"3;
"S \NAC"
BN"21"7;
%"TAP"
"1","(-575,3025)","2","standard","I169";
;
CDS_LIB"standard"
BODY_TYPE"PLUMBING"
HDL_TAP"TRUE";
"B \NAC \NWC"4;
"S \NAC"
BN"10"42;
%"TAP"
"1","(-575,3075)","2","standard","I170";
;
CDS_LIB"standard"
BODY_TYPE"PLUMBING"
HDL_TAP"TRUE";
"B \NAC \NWC"4;
"S \NAC"
BN"11"41;
%"TAP"
"1","(-400,1775)","2","standard","I171";
;
CDS_LIB"standard"
BODY_TYPE"PLUMBING"
HDL_TAP"TRUE";
"B \NAC \NWC"3;
"S \NAC"
BN"10"18;
%"TAP"
"1","(-400,1825)","2","standard","I172";
;
CDS_LIB"standard"
BODY_TYPE"PLUMBING"
HDL_TAP"TRUE";
"B \NAC \NWC"3;
"S \NAC"
BN"11"17;
%"TAP"
"1","(-400,1425)","2","standard","I173";
;
CDS_LIB"standard"
BODY_TYPE"PLUMBING"
HDL_TAP"TRUE";
"B \NAC \NWC"3;
"S \NAC"
BN"3"25;
%"TAP"
"1","(-400,1525)","2","standard","I174";
;
CDS_LIB"standard"
BODY_TYPE"PLUMBING"
HDL_TAP"TRUE";
"B \NAC \NWC"3;
"S \NAC"
BN"5"23;
%"TAP"
"1","(-575,2675)","2","standard","I175";
;
CDS_LIB"standard"
BODY_TYPE"PLUMBING"
HDL_TAP"TRUE";
"B \NAC \NWC"4;
"S \NAC"
BN"3"49;
%"TAP"
"1","(-575,2775)","2","standard","I176";
;
CDS_LIB"standard"
BODY_TYPE"PLUMBING"
HDL_TAP"TRUE";
"B \NAC \NWC"4;
"S \NAC"
BN"5"47;
%"TAP"
"1","(-400,2975)","2","standard","I19";
;
CDS_LIB"standard"
BODY_TYPE"PLUMBING"
HDL_TAP"TRUE";
"B \NAC \NWC"3;
"S \NAC"
BN"9"43;
%"TAP"
"1","(-400,2925)","2","standard","I21";
;
CDS_LIB"standard"
BODY_TYPE"PLUMBING"
HDL_TAP"TRUE";
"B \NAC \NWC"3;
"S \NAC"
BN"8"44;
%"TAP"
"1","(-400,3625)","2","standard","I34";
;
CDS_LIB"standard"
BODY_TYPE"PLUMBING"
HDL_TAP"TRUE";
"B \NAC \NWC"3;
"S \NAC"
BN"22"30;
%"TAP"
"1","(2975,2925)","0","standard","I52";
;
CDS_LIB"standard"
BODY_TYPE"PLUMBING"
HDL_TAP"TRUE";
"B \NAC \NWC"1;
"S \NAC"
BN"8"92;
%"TAP"
"1","(2975,2975)","0","standard","I53";
;
CDS_LIB"standard"
BODY_TYPE"PLUMBING"
HDL_TAP"TRUE";
"B \NAC \NWC"1;
"S \NAC"
BN"9"91;
%"TAP"
"1","(2975,3075)","0","standard","I54";
;
CDS_LIB"standard"
BODY_TYPE"PLUMBING"
HDL_TAP"TRUE";
"B \NAC \NWC"1;
"S \NAC"
BN"11"89;
%"TAP"
"1","(2975,3025)","0","standard","I55";
;
CDS_LIB"standard"
BODY_TYPE"PLUMBING"
HDL_TAP"TRUE";
"B \NAC \NWC"1;
"S \NAC"
BN"10"90;
%"TAP"
"1","(2975,3225)","0","standard","I58";
;
CDS_LIB"standard"
BODY_TYPE"PLUMBING"
HDL_TAP"TRUE";
"B \NAC \NWC"1;
"S \NAC"
BN"14"86;
%"TAP"
"1","(2975,3325)","0","standard","I59";
;
CDS_LIB"standard"
BODY_TYPE"PLUMBING"
HDL_TAP"TRUE";
"B \NAC \NWC"1;
"S \NAC"
BN"16"84;
%"TAP"
"1","(2975,3375)","0","standard","I61";
;
CDS_LIB"standard"
BODY_TYPE"PLUMBING"
HDL_TAP"TRUE";
"B \NAC \NWC"1;
"S \NAC"
BN"17"83;
%"TAP"
"1","(2975,3425)","0","standard","I62";
;
CDS_LIB"standard"
BODY_TYPE"PLUMBING"
HDL_TAP"TRUE";
"B \NAC \NWC"1;
"S \NAC"
BN"18"82;
%"TAP"
"1","(2975,3475)","0","standard","I64";
;
CDS_LIB"standard"
BODY_TYPE"PLUMBING"
HDL_TAP"TRUE";
"B \NAC \NWC"1;
"S \NAC"
BN"19"81;
%"TAP"
"1","(2975,3675)","0","standard","I66";
;
CDS_LIB"standard"
BODY_TYPE"PLUMBING"
HDL_TAP"TRUE";
"B \NAC \NWC"1;
"S \NAC"
BN"23"77;
%"SOCKET4677_AZIF0045P001C01CS"
"22","(1300,2475)","0","pure_quanta","I70";
;
PART_NUMBER"DGA^7000023"
VALUE"SOCKET4677_AZIF0045-P001C01CS"
MATERIAL"IO"
PART_TYPE"SMLF"
$LOCATION"U2"
CDS_LMAN_SYM_OUTLINE"-1050,1350,1050,-1350"
NEEDS_NO_SIZE"TRUE"
CDS_LIB"pure_quanta"
CDS_LOCATION"U2"
$SEC"22"
CDS_SEC"22";
"UPI0_TX_DP0"
$PN"J3"100;
"UPI0_TX_DP1"
$PN"L3"99;
"UPI0_TX_DP2"
$PN"P2"98;
"UPI0_TX_DP3"
$PN"R3"97;
"UPI0_TX_DP4"
$PN"V2"96;
"UPI0_TX_DP5"
$PN"W3"95;
"UPI0_TX_DP6"
$PN"AB2"94;
"UPI0_TX_DP7"
$PN"AC3"93;
"UPI0_TX_DP8"
$PN"AE1"92;
"UPI0_TX_DP9"
$PN"AG3"91;
"UPI0_TX_DP10"
$PN"AJ1"90;
"UPI0_TX_DP11"
$PN"AL3"89;
"UPI0_TX_DP12"
$PN"AN1"88;
"UPI0_TX_DP13"
$PN"AR3"87;
"UPI0_TX_DP14"
$PN"AV2"86;
"UPI0_TX_DP15"
$PN"AW3"85;
"UPI0_TX_DP16"
$PN"BA1"84;
"UPI0_TX_DP17"
$PN"BC3"83;
"UPI0_TX_DP18"
$PN"BE1"82;
"UPI0_TX_DP19"
$PN"BG3"81;
"UPI0_TX_DP20"
$PN"BJ1"80;
"UPI0_TX_DP21"
$PN"BL3"79;
"UPI0_TX_DP22"
$PN"BN3"78;
"UPI0_TX_DP23"
$PN"BU3"77;
"UPI0_TX_DN0"
$PN"K4"76;
"UPI0_TX_DN1"
$PN"M2"75;
"UPI0_TX_DN2"
$PN"N1"74;
"UPI0_TX_DN3"
$PN"T2"73;
"UPI0_TX_DN4"
$PN"U1"72;
"UPI0_TX_DN5"
$PN"Y2"71;
"UPI0_TX_DN6"
$PN"AA1"70;
"UPI0_TX_DN7"
$PN"AD2"69;
"UPI0_TX_DN8"
$PN"AF2"68;
"UPI0_TX_DN9"
$PN"AH2"67;
"UPI0_TX_DN10"
$PN"AK2"66;
"UPI0_TX_DN11"
$PN"AM2"65;
"UPI0_TX_DN12"
$PN"AP2"64;
"UPI0_TX_DN13"
$PN"AT2"63;
"UPI0_TX_DN14"
$PN"AU1"62;
"UPI0_TX_DN15"
$PN"AY2"61;
"UPI0_TX_DN16"
$PN"BB2"60;
"UPI0_TX_DN17"
$PN"BD2"59;
"UPI0_TX_DN18"
$PN"BF2"58;
"UPI0_TX_DN19"
$PN"BH2"57;
"UPI0_TX_DN20"
$PN"BK2"56;
"UPI0_TX_DN21"
$PN"BM2"55;
"UPI0_TX_DN22"
$PN"BR3"54;
"UPI0_TX_DN23"
$PN"BT2"53;
"UPI0_RX_DP0"
$PN"L7"52;
"UPI0_RX_DP1"
$PN"M6"51;
"UPI0_RX_DP2"
$PN"R7"50;
"UPI0_RX_DP3"
$PN"T6"49;
"UPI0_RX_DP4"
$PN"W7"48;
"UPI0_RX_DP5"
$PN"Y6"47;
"UPI0_RX_DP6"
$PN"AC7"46;
"UPI0_RX_DP7"
$PN"AD6"45;
"UPI0_RX_DP8"
$PN"AG7"44;
"UPI0_RX_DP9"
$PN"AJ5"43;
"UPI0_RX_DP10"
$PN"AL7"42;
"UPI0_RX_DP11"
$PN"AM6"41;
"UPI0_RX_DP12"
$PN"AR7"40;
"UPI0_RX_DP13"
$PN"AT6"39;
"UPI0_RX_DP14"
$PN"AW7"38;
"UPI0_RX_DP15"
$PN"AY6"37;
"UPI0_RX_DP16"
$PN"BC7"36;
"UPI0_RX_DP17"
$PN"BD6"35;
"UPI0_RX_DP18"
$PN"BG7"34;
"UPI0_RX_DP19"
$PN"BH6"33;
"UPI0_RX_DP20"
$PN"BL7"32;
"UPI0_RX_DP21"
$PN"BM6"31;
"UPI0_RX_DP22"
$PN"BP6"30;
"UPI0_RX_DP23"
$PN"BT6"29;
"UPI0_RX_DN0"
$PN"K6"28;
"UPI0_RX_DN1"
$PN"N5"27;
"UPI0_RX_DN2"
$PN"P6"26;
"UPI0_RX_DN3"
$PN"U5"25;
"UPI0_RX_DN4"
$PN"V6"24;
"UPI0_RX_DN5"
$PN"AA5"23;
"UPI0_RX_DN6"
$PN"AB6"22;
"UPI0_RX_DN7"
$PN"AE5"21;
"UPI0_RX_DN8"
$PN"AF6"20;
"UPI0_RX_DN9"
$PN"AH6"19;
"UPI0_RX_DN10"
$PN"AK6"18;
"UPI0_RX_DN11"
$PN"AN5"17;
"UPI0_RX_DN12"
$PN"AP6"16;
"UPI0_RX_DN13"
$PN"AU5"15;
"UPI0_RX_DN14"
$PN"AV6"14;
"UPI0_RX_DN15"
$PN"BA5"13;
"UPI0_RX_DN16"
$PN"BB6"12;
"UPI0_RX_DN17"
$PN"BE5"11;
"UPI0_RX_DN18"
$PN"BF6"10;
"UPI0_RX_DN19"
$PN"BJ5"9;
"UPI0_RX_DN20"
$PN"BK6"8;
"UPI0_RX_DN21"
$PN"BN5"7;
"UPI0_RX_DN22"
$PN"BR7"6;
"UPI0_RX_DN23"
$PN"BU5"5;
%"TAP"
"1","(-575,1725)","2","standard","I77";
;
CDS_LIB"standard"
BODY_TYPE"PLUMBING"
HDL_TAP"TRUE";
"B \NAC \NWC"4;
"S \NAC"
BN"9"19;
%"TAP"
"1","(-575,1675)","2","standard","I78";
;
CDS_LIB"standard"
BODY_TYPE"PLUMBING"
HDL_TAP"TRUE";
"B \NAC \NWC"4;
"S \NAC"
BN"8"20;
%"TAP"
"1","(-575,1625)","2","standard","I79";
;
CDS_LIB"standard"
BODY_TYPE"PLUMBING"
HDL_TAP"TRUE";
"B \NAC \NWC"4;
"S \NAC"
BN"7"21;
%"TAP"
"1","(-575,1575)","2","standard","I80";
;
CDS_LIB"standard"
BODY_TYPE"PLUMBING"
HDL_TAP"TRUE";
"B \NAC \NWC"4;
"S \NAC"
BN"6"22;
%"TAP"
"1","(-575,1475)","2","standard","I82";
;
CDS_LIB"standard"
BODY_TYPE"PLUMBING"
HDL_TAP"TRUE";
"B \NAC \NWC"4;
"S \NAC"
BN"4"24;
%"TAP"
"1","(-575,1275)","2","standard","I84";
;
CDS_LIB"standard"
BODY_TYPE"PLUMBING"
HDL_TAP"TRUE";
"B \NAC \NWC"4;
"S \NAC"
BN"0"28;
%"TAP"
"1","(-575,1325)","2","standard","I85";
;
CDS_LIB"standard"
BODY_TYPE"PLUMBING"
HDL_TAP"TRUE";
"B \NAC \NWC"4;
"S \NAC"
BN"1"27;
%"TAP"
"1","(-575,1375)","2","standard","I86";
;
CDS_LIB"standard"
BODY_TYPE"PLUMBING"
HDL_TAP"TRUE";
"B \NAC \NWC"4;
"S \NAC"
BN"2"26;
%"TAP"
"1","(-575,2375)","2","standard","I95";
;
CDS_LIB"standard"
BODY_TYPE"PLUMBING"
HDL_TAP"TRUE";
"B \NAC \NWC"4;
"S \NAC"
BN"22"6;
%"TAP"
"1","(-400,2575)","2","standard","I97";
;
CDS_LIB"standard"
BODY_TYPE"PLUMBING"
HDL_TAP"TRUE";
"B \NAC \NWC"3;
"S \NAC"
BN"1"51;
%"TAP"
"1","(-400,2625)","2","standard","I98";
;
CDS_LIB"standard"
BODY_TYPE"PLUMBING"
HDL_TAP"TRUE";
"B \NAC \NWC"3;
"S \NAC"
BN"2"50;
END.
